# S9S_MB_2U (Grand Teton) — schematic netlist excerpt (pin names and nets, part order shuffled) for the footprints in the layout excerpt that follows; sources: Cadence DE-HDL packaged netlist, KiCad conversion of 03242023_DA0F0TMBIJ0_F0T_Motherboard_J_brd_V01_OCP.brd

PR1328  Q_RES  7.32K 0.1% CHIP  pkg 0402LF  page 262 : A = P1V05_PCH_AUX_FB ; B = SH_P1V05_PCH_AUX_P

X44  TP_TDR_4P_FTS  TP_TDR_4P_DIP EMPTY  pkg TH  page 310
  S1  = UNNAMED_310_TPTDR4PFTS_I5_S2
  P1  = T1_GND
  P2  = T1_GND
  S2  = UNNAMED_310_TPTDR4PFTS_I5_S1

(kicad_pcb
	(version 20260206)
	(generator "pcbnew")
	(generator_version "10.0")
	(general
		(thickness 1.6)
		(legacy_teardrops no)
	)
	(paper "A4")
	(title_block
		(title "03242023_DA0F0TMBIJ0_F0T_Motherboard_J_brd_V01_OCP.brd")
		(comment 1 "Grand Teton / footprints 3558-3559 of 6105")
	)
	(layers
		(0 "F.Cu" signal "TOP")
		(4 "In1.Cu" signal "GND")
		(6 "In2.Cu" signal "IN1")
		(8 "In3.Cu" signal "GND1")
		(10 "In4.Cu" signal "IN2")
		(12 "In5.Cu" signal "GND2")
		(14 "In6.Cu" signal "IN3")
		(16 "In7.Cu" signal "GND3")
		(18 "In8.Cu" signal "VCC")
		(20 "In9.Cu" signal "VCC1")
		(22 "In10.Cu" signal "GND4")
		(24 "In11.Cu" signal "IN4")
		(26 "In12.Cu" signal "GND5")
		(28 "In13.Cu" signal "IN5")
		(30 "In14.Cu" signal "GND6")
		(32 "In15.Cu" signal "IN6")
		(34 "In16.Cu" signal "GND7")
		(2 "B.Cu" signal "BOTTOM")
		(9 "F.Adhes" user "F.Adhesive")
		(11 "B.Adhes" user "B.Adhesive")
		(13 "F.Paste" user "Package Geometry/Pastemask Top")
		(15 "B.Paste" user "Package Geometry/Pastemask Bottom")
		(5 "F.SilkS" user "Ref Des/Silkscreen Top")
		(7 "B.SilkS" user "Ref Des/Silkscreen Bottom")
		(1 "F.Mask" user "Board Geometry/Soldermask Top")
		(3 "B.Mask" user "Board Geometry/Soldermask Bottom")
		(17 "Dwgs.User" user "User.Drawings")
		(19 "Cmts.User" user "User.Comments")
		(21 "Eco1.User" user "User.Eco1")
		(23 "Eco2.User" user "User.Eco2")
		(25 "Edge.Cuts" user "Board Geometry/Outline")
		(27 "Margin" user)
		(31 "F.CrtYd" user "Package Geometry/Place Bound Top")
		(29 "B.CrtYd" user "Package Geometry/Place Bound Bottom")
		(35 "F.Fab" user "Ref Des/Assembly Top")
		(33 "B.Fab" user "Ref Des/Assembly Bottom")
	)
	(footprint ""
		(layer "F.Cu")
		(at 260.561582 -76.533502)
		(property "Reference" "PR1328"
			(at 0 0 0)
			(layer "F.SilkS")
			(hide yes)
			(effects
				(font
					(size 1.27 1.27)
				)
			)
		)
		(property "Value" ""
			(at 0 0 0)
			(layer "F.Fab")
			(effects
				(font
					(size 1.27 1.27)
				)
			)
		)
		(duplicate_pad_numbers_are_jumpers no)
		(fp_line
			(start -0.7874 -0.4064)
			(end 0.7874 -0.4064)
			(stroke
				(width 0.1524)
				(type default)
			)
			(layer "F.SilkS")
		)
		(fp_line
			(start -0.7874 0.4064)
			(end -0.7874 -0.4064)
			(stroke
				(width 0.1524)
				(type default)
			)
			(layer "F.SilkS")
		)
		(fp_line
			(start 0.7874 -0.4064)
			(end 0.7874 0.4064)
			(stroke
				(width 0.1524)
				(type default)
			)
			(layer "F.SilkS")
		)
		(fp_line
			(start 0.7874 0.4064)
			(end -0.7874 0.4064)
			(stroke
				(width 0.1524)
				(type default)
			)
			(layer "F.SilkS")
		)
		(fp_line
			(start -0.67945 -0.305054)
			(end -0.12065 -0.305054)
			(stroke
				(width 0.1)
				(type default)
			)
			(layer "F.Fab")
		)
		(fp_line
			(start -0.67945 0.3048)
			(end -0.67945 -0.305054)
			(stroke
				(width 0.1)
				(type default)
			)
			(layer "F.Fab")
		)
		(fp_line
			(start -0.12065 -0.305054)
			(end -0.12065 -0.2794)
			(stroke
				(width 0.1)
				(type default)
			)
			(layer "F.Fab")
		)
		(fp_line
			(start -0.12065 -0.2794)
			(end 0.12065 -0.2794)
			(stroke
				(width 0.1)
				(type default)
			)
			(layer "F.Fab")
		)
		(fp_line
			(start -0.12065 0.2794)
			(end -0.12065 0.3048)
			(stroke
				(width 0.1)
				(type default)
			)
			(layer "F.Fab")
		)
		(fp_line
			(start -0.12065 0.3048)
			(end -0.67945 0.3048)
			(stroke
				(width 0.1)
				(type default)
			)
			(layer "F.Fab")
		)
		(fp_line
			(start 0.120396 0.2794)
			(end -0.12065 0.2794)
			(stroke
				(width 0.1)
				(type default)
			)
			(layer "F.Fab")
		)
		(fp_line
			(start 0.120396 0.3048)
			(end 0.120396 0.2794)
			(stroke
				(width 0.1)
				(type default)
			)
			(layer "F.Fab")
		)
		(fp_line
			(start 0.12065 -0.3048)
			(end 0.67945 -0.3048)
			(stroke
				(width 0.1)
				(type default)
			)
			(layer "F.Fab")
		)
		(fp_line
			(start 0.12065 -0.2794)
			(end 0.12065 -0.3048)
			(stroke
				(width 0.1)
				(type default)
			)
			(layer "F.Fab")
		)
		(fp_line
			(start 0.67945 -0.3048)
			(end 0.67945 0.3048)
			(stroke
				(width 0.1)
				(type default)
			)
			(layer "F.Fab")
		)
		(fp_line
			(start 0.67945 0.3048)
			(end 0.120396 0.3048)
			(stroke
				(width 0.1)
				(type default)
			)
			(layer "F.Fab")
		)
		(pad "1" smd circle
			(at -0.40005 0)
			(size 0 0)
			(layers "F.Cu" "F.Mask" "F.Paste")
			(net "P1V05_PCH_AUX_FB")
		)
		(pad "2" smd circle
			(at 0.40005 0)
			(size 0 0)
			(layers "F.Cu" "F.Mask" "F.Paste")
			(net "SH_P1V05_PCH_AUX_P")
		)
	)
	(footprint ""
		(layer "F.Cu")
		(at 477.30537 -148.043392 90)
		(property "Reference" "X44"
			(at -3.136392 -1.5367 90)
			(unlocked yes)
			(layer "F.SilkS")
			(effects
				(font
					(size 0.7874 0.5842)
					(thickness 0.1524)
				)
				(justify left)
			)
		)
		(property "Value" ""
			(at 0 0 90)
			(layer "F.Fab")
			(effects
				(font
					(size 1.27 1.27)
				)
			)
		)
		(property "Device Type" "TP_TDR_4P_FTS_TH-TP_TDR_4P_DIPA"
			(at 1.30175 1.27 180)
			(unlocked yes)
			(layer "F.Fab")
			(hide yes)
			(effects
				(font
					(size 0.635 0.4064)
					(thickness 0.1524)
				)
			)
		)
		(property "User Part Number" "N_A"
			(at 1.30175 1.27 180)
			(unlocked yes)
			(layer "Cmts.User")
			(hide yes)
			(effects
				(font
					(size 0.635 0.4064)
					(thickness 0.1524)
				)
			)
		)
		(duplicate_pad_numbers_are_jumpers no)
		(fp_line
			(start 2.54 -1.27)
			(end 0 -1.27)
			(stroke
				(width 0.1524)
				(type default)
			)
			(layer "F.SilkS")
		)
		(fp_line
			(start 0 -1.27)
			(end 0 -0.635)
			(stroke
				(width 0.1524)
				(type default)
			)
			(layer "F.SilkS")
		)
		(fp_line
			(start 2.54 -1.1303)
			(end 2.54 -1.27)
			(stroke
				(width 0.1524)
				(type default)
			)
			(layer "F.SilkS")
		)
		(fp_line
			(start 0 0.635)
			(end 0 1.905)
			(stroke
				(width 0.1524)
				(type default)
			)
			(layer "F.SilkS")
		)
		(fp_line
			(start 2.54 1.4097)
			(end 2.54 1.1303)
			(stroke
				(width 0.1524)
				(type default)
			)
			(layer "F.SilkS")
		)
		(fp_line
			(start 0 3.175)
			(end 0 3.81)
			(stroke
				(width 0.1524)
				(type default)
			)
			(layer "F.SilkS")
		)
		(fp_line
			(start 2.54 3.81)
			(end 2.54 3.6703)
			(stroke
				(width 0.1524)
				(type default)
			)
			(layer "F.SilkS")
		)
		(fp_line
			(start 0 3.81)
			(end 2.54 3.81)
			(stroke
				(width 0.1524)
				(type default)
			)
			(layer "F.SilkS")
		)
		(fp_poly
			(pts
				(xy -0.761746 0) (xy -2.285746 -0.762) (xy -2.285746 0.762)
			)
			(stroke
				(width 0)
				(type default)
			)
			(fill yes)
			(layer "F.SilkS")
		)
		(fp_line
			(start 2.54 -1.27)
			(end 0 -1.27)
			(stroke
				(width 0.1)
				(type default)
			)
			(layer "F.Fab")
		)
		(fp_line
			(start 0 -1.27)
			(end 0 3.81)
			(stroke
				(width 0.1)
				(type default)
			)
			(layer "F.Fab")
		)
		(fp_line
			(start 2.54 3.81)
			(end 2.54 -1.27)
			(stroke
				(width 0.1)
				(type default)
			)
			(layer "F.Fab")
		)
		(fp_line
			(start 0 3.81)
			(end 2.54 3.81)
			(stroke
				(width 0.1)
				(type default)
			)
			(layer "F.Fab")
		)
		(fp_poly
			(pts
				(xy -0.761746 0) (xy -2.285746 -0.762) (xy -2.285746 0.762)
			)
			(stroke
				(width 0)
				(type default)
			)
			(fill yes)
			(layer "F.Fab")
		)
		(pad "1" thru_hole circle
			(at 0 0 90)
			(size 1.0033 1.0033)
			(drill 0.249936)
			(layers "*.Cu" "*.Mask")
			(remove_unused_layers no)
			(net "TDR_DIFF_85_NECK_IN3_DN")
			(clearance 0.10795)
			(thermal_gap 0.10795)
			(padstack
				(mode front_inner_back)
				(layer "Inner"
					(shape circle)
					(size 0.8001 0.8001)
					(clearance 0.1524)
				)
				(layer "B.Cu"
					(shape circle)
					(size 1.0033 1.0033)
					(clearance 0.10795)
				)
			)
		)
		(pad "2" thru_hole circle
			(at 2.54 0 90)
			(size 1.9939 1.9939)
			(drill 0.249936)
			(layers "*.Cu" "*.Mask")
			(remove_unused_layers no)
			(net "T1_GND")
			(clearance 0.10795)
			(thermal_gap 0.10795)
			(padstack
				(mode front_inner_back)
				(layer "Inner"
					(shape circle)
					(size 0.8001 0.8001)
					(clearance 0.1524)
				)
				(layer "B.Cu"
					(shape circle)
					(size 1.9939 1.9939)
					(clearance 0.10795)
				)
			)
		)
		(pad "3" thru_hole circle
			(at 2.54 2.54 90)
			(size 1.9939 1.9939)
			(drill 0.249936)
			(layers "*.Cu" "*.Mask")
			(remove_unused_layers no)
			(net "T1_GND")
			(clearance 0.10795)
			(thermal_gap 0.10795)
			(padstack
				(mode front_inner_back)
				(layer "Inner"
					(shape circle)
					(size 0.8001 0.8001)
					(clearance 0.1524)
				)
				(layer "B.Cu"
					(shape circle)
					(size 1.9939 1.9939)
					(clearance 0.10795)
				)
			)
		)
		(pad "4" thru_hole circle
			(at 0 2.54 90)
			(size 1.0033 1.0033)
			(drill 0.249936)
			(layers "*.Cu" "*.Mask")
			(remove_unused_layers no)
			(net "TDR_DIFF_85_NECK_IN3_DP")
			(clearance 0.10795)
			(thermal_gap 0.10795)
			(padstack
				(mode front_inner_back)
				(layer "Inner"
					(shape circle)
					(size 0.8001 0.8001)
					(clearance 0.1524)
				)
				(layer "B.Cu"
					(shape circle)
					(size 1.0033 1.0033)
					(clearance 0.10795)
				)
			)
		)
	)
)
